# BASEBOARD_FAB2 (Tioga Pass) — schematic netlist excerpt (pin names and nets, part order shuffled) for the footprints in the layout excerpt that follows; sources: Cadence DE-HDL packaged netlist, KiCad conversion of Wiwynn_Tioga_Pass_MB.brd

Q1W5  FET_N  2N7002 FET  pkg SOT23LF  page 199
  GATE  = A_HSC_HIGH_EN
  SRC  = GND
  DRN  = A_HSC_LOW_GATE

C3M27  CAP_A  1.0UF 6.3V 10% X6S  pkg 0402V  page 127 : A = P1V05_PCH_STBY_VCCA_XTAL ; B = GND
C3R4  CAPP  470UF 2.5V 20% ALUM  pkg 3018  page 194 : A = PVCCMCP_CPU0 ; B = GND

(kicad_pcb
	(version 20260206)
	(generator "pcbnew")
	(generator_version "10.0")
	(general
		(thickness 1.6)
		(legacy_teardrops no)
	)
	(paper "A4")
	(title_block
		(title "Wiwynn_Tioga_Pass_MB.brd")
		(comment 1 "Tioga Pass / footprints 4273-4275 of 4770")
	)
	(layers
		(0 "F.Cu" signal "TOP")
		(4 "In1.Cu" signal "L2GND")
		(6 "In2.Cu" signal "L3")
		(8 "In3.Cu" signal "L4GND")
		(10 "In4.Cu" signal "L5")
		(12 "In5.Cu" signal "L6GND")
		(14 "In6.Cu" signal "L7VCC")
		(16 "In7.Cu" signal "L8VCC")
		(18 "In8.Cu" signal "L9GND")
		(20 "In9.Cu" signal "L10")
		(22 "In10.Cu" signal "L11GND")
		(24 "In11.Cu" signal "L12")
		(26 "In12.Cu" signal "L13GND")
		(2 "B.Cu" signal "BOTTOM")
		(9 "F.Adhes" user "F.Adhesive")
		(11 "B.Adhes" user "B.Adhesive")
		(13 "F.Paste" user "Package Geometry/Pastemask Top")
		(15 "B.Paste" user "Package Geometry/Pastemask Bottom")
		(5 "F.SilkS" user "Ref Des/Silkscreen Top")
		(7 "B.SilkS" user "Ref Des/Silkscreen Bottom")
		(1 "F.Mask" user "Board Geometry/Soldermask Top")
		(3 "B.Mask" user "Board Geometry/Soldermask Bottom")
		(17 "Dwgs.User" user "User.Drawings")
		(19 "Cmts.User" user "User.Comments")
		(21 "Eco1.User" user "User.Eco1")
		(23 "Eco2.User" user "User.Eco2")
		(25 "Edge.Cuts" user "Board Geometry/Outline")
		(27 "Margin" user)
		(31 "F.CrtYd" user "Package Geometry/Place Bound Top")
		(29 "B.CrtYd" user "Package Geometry/Place Bound Bottom")
		(35 "F.Fab" user "Ref Des/Assembly Top")
		(33 "B.Fab" user "Ref Des/Assembly Bottom")
	)
	(footprint ""
		(layer "B.Cu")
		(at 382.905 -133.604 90)
		(property "Reference" "C3M27"
			(at 0 0 90)
			(layer "B.SilkS")
			(hide yes)
			(effects
				(font
					(size 1.27 1.27)
				)
				(justify mirror)
			)
		)
		(property "Value" ""
			(at 0 0 90)
			(layer "B.Fab")
			(effects
				(font
					(size 1.27 1.27)
				)
				(justify mirror)
			)
		)
		(duplicate_pad_numbers_are_jumpers no)
		(fp_poly
			(pts
				(xy -0.3048 -0.1016) (xy -0.3048 0.9906) (xy 0.3048 0.9906) (xy 0.3048 -0.1016)
			)
			(stroke
				(width 0)
				(type default)
			)
			(fill no)
			(layer "B.CrtYd")
		)
		(fp_line
			(start 0.3048 -0.1016)
			(end 0.3048 0.9906)
			(stroke
				(width 0.1)
				(type default)
			)
			(layer "B.Fab")
		)
		(fp_line
			(start -0.3048 -0.1016)
			(end 0.3048 -0.1016)
			(stroke
				(width 0.1)
				(type default)
			)
			(layer "B.Fab")
		)
		(fp_line
			(start 0.3048 0.9906)
			(end -0.3048 0.9906)
			(stroke
				(width 0.1)
				(type default)
			)
			(layer "B.Fab")
		)
		(fp_line
			(start -0.3048 0.9906)
			(end -0.3048 -0.1016)
			(stroke
				(width 0.1)
				(type default)
			)
			(layer "B.Fab")
		)
		(pad "1" smd rect
			(at 0 0 270)
			(size 0.508 0.508)
			(layers "B.Cu" "B.Mask" "B.Paste")
			(net "P1V05_PCH_STBY_VCCA_XTAL")
		)
		(pad "2" smd rect
			(at 0 0.889 270)
			(size 0.508 0.508)
			(layers "B.Cu" "B.Mask" "B.Paste")
			(net "GND")
		)
		(zone
			(layer "B.Cu")
			(hatch none 0.5)
			(connect_pads
				(clearance 0)
			)
			(min_thickness 0.25)
			(keepout
				(tracks allowed)
				(vias not_allowed)
				(pads allowed)
				(copperpour not_allowed)
				(footprints allowed)
			)
			(placement
				(enabled no)
				(sheetname "")
			)
			(fill
				(thermal_gap 0.5)
				(thermal_bridge_width 0.5)
				(island_removal_mode 0)
			)
			(polygon
				(pts
					(xy 383.159 -133.858) (xy 383.159 -133.35) (xy 383.54 -133.35) (xy 383.54 -133.858)
				)
			)
		)
		(zone
			(layer "B.Cu")
			(hatch none 0.5)
			(connect_pads
				(clearance 0)
			)
			(min_thickness 0.25)
			(keepout
				(tracks not_allowed)
				(vias allowed)
				(pads allowed)
				(copperpour not_allowed)
				(footprints allowed)
			)
			(placement
				(enabled no)
				(sheetname "")
			)
			(fill
				(thermal_gap 0.5)
				(thermal_bridge_width 0.5)
				(island_removal_mode 0)
			)
			(polygon
				(pts
					(xy 383.54 -133.858) (xy 383.54 -133.35) (xy 383.159 -133.35) (xy 383.159 -133.858)
				)
			)
		)
	)
	(footprint ""
		(layer "B.Cu")
		(at 14.445488 -80.7847)
		(property "Reference" "Q1W5"
			(at 0.229362 -1.2065 0)
			(unlocked yes)
			(layer "B.SilkS")
			(effects
				(font
					(size 0.4064 0.254)
					(thickness 0.1524)
				)
				(justify left mirror)
			)
		)
		(property "Value" ""
			(at 0 0 0)
			(layer "B.Fab")
			(effects
				(font
					(size 1.27 1.27)
				)
				(justify mirror)
			)
		)
		(duplicate_pad_numbers_are_jumpers no)
		(fp_line
			(start -1.778 -0.5715)
			(end -1.778 0.3175)
			(stroke
				(width 0.1524)
				(type default)
			)
			(layer "B.SilkS")
		)
		(fp_line
			(start -1.778 2.4765)
			(end -1.778 1.5875)
			(stroke
				(width 0.1524)
				(type default)
			)
			(layer "B.SilkS")
		)
		(fp_line
			(start -0.9525 -0.5715)
			(end -1.778 -0.5715)
			(stroke
				(width 0.1524)
				(type default)
			)
			(layer "B.SilkS")
		)
		(fp_line
			(start -0.9525 2.4765)
			(end -1.778 2.4765)
			(stroke
				(width 0.1524)
				(type default)
			)
			(layer "B.SilkS")
		)
		(fp_line
			(start -0.381 0.635)
			(end -0.381 1.27)
			(stroke
				(width 0.1524)
				(type default)
			)
			(layer "B.SilkS")
		)
		(fp_circle
			(center 0.9525 -0.9271)
			(end 1.0795 -0.9271)
			(stroke
				(width 0.254)
				(type default)
			)
			(fill no)
			(layer "B.SilkS")
		)
		(fp_poly
			(pts
				(xy -1.778 2.4765) (xy -0.381 2.4765) (xy -0.381 -0.5715) (xy -1.778 -0.5715)
			)
			(stroke
				(width 0)
				(type default)
			)
			(fill no)
			(layer "B.CrtYd")
		)
		(fp_line
			(start -1.778 -0.5715)
			(end -0.381 -0.5715)
			(stroke
				(width 0.1)
				(type default)
			)
			(layer "B.Fab")
		)
		(fp_line
			(start -1.778 2.4765)
			(end -1.778 -0.5715)
			(stroke
				(width 0.1)
				(type default)
			)
			(layer "B.Fab")
		)
		(fp_line
			(start -0.381 -0.5715)
			(end -0.381 2.4765)
			(stroke
				(width 0.1)
				(type default)
			)
			(layer "B.Fab")
		)
		(fp_line
			(start -0.381 2.4765)
			(end -1.778 2.4765)
			(stroke
				(width 0.1)
				(type default)
			)
			(layer "B.Fab")
		)
		(fp_circle
			(center 0.9525 -0.9271)
			(end 1.0795 -0.9271)
			(stroke
				(width 0.254)
				(type default)
			)
			(fill no)
			(layer "B.Fab")
		)
		(pad "1" smd rect
			(at 0 0 180)
			(size 1.143 0.508)
			(layers "B.Cu" "B.Mask" "B.Paste")
			(net "A_HSC_HIGH_EN")
		)
		(pad "2" smd rect
			(at 0 1.905 180)
			(size 1.143 0.508)
			(layers "B.Cu" "B.Mask" "B.Paste")
			(net "GND")
		)
		(pad "3" smd rect
			(at -2.159 0.9525 180)
			(size 1.143 0.508)
			(layers "B.Cu" "B.Mask" "B.Paste")
			(net "A_HSC_LOW_GATE")
		)
	)
	(footprint ""
		(layer "B.Cu")
		(at 334.264 -45.974 180)
		(property "Reference" "C3R4"
			(at -3.14833 3.429 270)
			(unlocked yes)
			(layer "B.SilkS")
			(effects
				(font
					(size 0.7874 0.5842)
					(thickness 0.1524)
				)
				(justify mirror)
			)
		)
		(property "Value" ""
			(at 0 0 0)
			(layer "B.Fab")
			(effects
				(font
					(size 1.27 1.27)
				)
				(justify mirror)
			)
		)
		(duplicate_pad_numbers_are_jumpers no)
		(fp_line
			(start 2.563114 1.633728)
			(end 1.6002 1.633728)
			(stroke
				(width 0.1524)
				(type default)
			)
			(layer "B.SilkS")
		)
		(fp_line
			(start 2.563114 -1.616456)
			(end 2.563114 1.633728)
			(stroke
				(width 0.1524)
				(type default)
			)
			(layer "B.SilkS")
		)
		(fp_line
			(start 2.286 7.366)
			(end 2.286 1.632712)
			(stroke
				(width 0.1524)
				(type default)
			)
			(layer "B.SilkS")
		)
		(fp_line
			(start 2.286 7.366)
			(end 1.60147 7.366)
			(stroke
				(width 0.1524)
				(type default)
			)
			(layer "B.SilkS")
		)
		(fp_line
			(start 1.6002 -1.616456)
			(end 2.563114 -1.616456)
			(stroke
				(width 0.1524)
				(type default)
			)
			(layer "B.SilkS")
		)
		(fp_line
			(start -1.6002 -1.616456)
			(end -2.504948 -1.616456)
			(stroke
				(width 0.1524)
				(type default)
			)
			(layer "B.SilkS")
		)
		(fp_line
			(start -2.286 7.366)
			(end -1.600708 7.366)
			(stroke
				(width 0.1524)
				(type default)
			)
			(layer "B.SilkS")
		)
		(fp_line
			(start -2.286 7.366)
			(end -2.286 1.63195)
			(stroke
				(width 0.1524)
				(type default)
			)
			(layer "B.SilkS")
		)
		(fp_line
			(start -2.504948 1.633728)
			(end -1.6002 1.633728)
			(stroke
				(width 0.1524)
				(type default)
			)
			(layer "B.SilkS")
		)
		(fp_line
			(start -2.504948 -1.616456)
			(end -2.504948 1.633728)
			(stroke
				(width 0.1524)
				(type default)
			)
			(layer "B.SilkS")
		)
		(fp_rect
			(start 2.286 7.366)
			(end -2.286 -0.254)
			(stroke
				(width 0)
				(type default)
			)
			(fill no)
			(layer "B.CrtYd")
		)
		(fp_line
			(start 2.286 7.366)
			(end 2.286 -0.254)
			(stroke
				(width 0.1)
				(type default)
			)
			(layer "B.Fab")
		)
		(fp_line
			(start 2.286 -0.254)
			(end -2.286 -0.254)
			(stroke
				(width 0.1)
				(type default)
			)
			(layer "B.Fab")
		)
		(fp_line
			(start -2.286 7.366)
			(end 2.286 7.366)
			(stroke
				(width 0.1)
				(type default)
			)
			(layer "B.Fab")
		)
		(fp_line
			(start -2.286 -0.254)
			(end -2.286 7.366)
			(stroke
				(width 0.1)
				(type default)
			)
			(layer "B.Fab")
		)
		(pad "1" smd rect
			(at 0 0)
			(size 2.54 3.048)
			(layers "B.Cu" "B.Mask" "B.Paste")
			(net "PVCCMCP_CPU0")
		)
		(pad "2" smd rect
			(at 0 7.112)
			(size 2.54 3.048)
			(layers "B.Cu" "B.Mask" "B.Paste")
			(net "GND")
		)
	)
)
